# T6G (Grand Teton) — schematic netlist excerpt (pin names and nets, part order shuffled) for the footprints in the layout excerpt that follows; sources: Cadence DE-HDL packaged netlist, KiCad conversion of 04192023_DAF0TMB3IC0_F0TG_MB_C_brd_V02_OCP.brd

J32  SCONN288_DDR506112002KQ  IO  pkg DDR288S_1-1VXC  page 102
  VIN_BULK0  = P12V_MEM_CPU1
  RFU0  = NC
  VIN_MGMT  = P3V3_AUX
  HSCL  = I3C_SPD_DDRE_CPU1_SCL
  HSDA  = I3C_SPD_DDRE_CPU1_SDA
  VSS0  = GND
  DQ0_A  = M_E_CPU1_SA_DQ<0>
  VSS1  = GND
  DQ1_A  = M_E_CPU1_SA_DQ<1>
  VSS2  = GND
  DQS0_A_T  = M_E_CPU1_SA_DQS_DP<0>
  DQS0_A_C  = M_E_CPU1_SA_DQS_DN<0>
  VSS3  = GND
  DQ4_A  = M_E_CPU1_SA_DQ<4>
  VSS4  = GND
  DQ5_A  = M_E_CPU1_SA_DQ<5>
  VSS5  = GND
  DQ8_A  = M_E_CPU1_SA_DQ<8>
  VSS6  = GND
  DQ9_A  = M_E_CPU1_SA_DQ<9>
  VSS7  = GND
  DQS1_A_T  = M_E_CPU1_SA_DQS_DP<1>
  DQS1_A_C  = M_E_CPU1_SA_DQS_DN<1>
  VSS8  = GND
  DQ12_A  = M_E_CPU1_SA_DQ<12>
  VSS9  = GND
  DQ13_A  = M_E_CPU1_SA_DQ<13>
  VSS10  = GND
  DQ16_A  = M_E_CPU1_SA_DQ<16>
  VSS11  = GND
  DQ17_A  = M_E_CPU1_SA_DQ<17>
  VSS12  = GND
  DQS2_A_T  = M_E_CPU1_SA_DQS_DP<2>
  DQS2_A_C  = M_E_CPU1_SA_DQS_DN<2>
  VSS13  = GND
  DQ20_A  = M_E_CPU1_SA_DQ<20>
  VSS14  = GND
  DQ21_A  = M_E_CPU1_SA_DQ<21>
  VSS15  = GND
  DQ24_A  = M_E_CPU1_SA_DQ<24>
  VSS16  = GND
  DQ25_A  = M_E_CPU1_SA_DQ<25>
  VSS17  = GND
  DQS3_A_T  = M_E_CPU1_SA_DQS_DP<3>
  DQS3_A_C  = M_E_CPU1_SA_DQS_DN<3>
  VSS18  = GND
  DQ28_A  = M_E_CPU1_SA_DQ<28>
  VSS19  = GND
  DQ29_A  = M_E_CPU1_SA_DQ<29>
  VSS20  = GND
  CB0_A  = M_E_CPU1_SA_CB<0>
  VSS21  = GND
  CB1_A  = M_E_CPU1_SA_CB<1>
  VSS22  = GND
  DQS4_A_T  = M_E_CPU1_SA_DQS_DP<4>
  DQS4_A_C  = M_E_CPU1_SA_DQS_DN<4>
  VSS23  = GND
  CB4_A  = M_E_CPU1_SA_CB<4>
  VSS24  = GND
  CB5_A  = M_E_CPU1_SA_CB<5>
  VSS25  = GND
  ALERT_N  = M_E_CPU1_ALERT_N
  VSS26  = GND
  CS0_A_N  = M_E_CPU1_SA_CS_N<0>
  VSS27  = GND
  CA0_A  = M_E_CPU1_SA_CA<0>
  VSS28  = GND
  CA2_A  = M_E_CPU1_SA_CA<2>
  VSS29  = GND
  CA4_A  = M_E_CPU1_SA_CA<4>
  VSS30  = GND
  CA6_A  = M_E_CPU1_SA_CA<6>
  VSS31  = GND
  PAR_A  = M_E_CPU1_SA_PAR
  VSS32  = GND
  CA0_B  = M_E_CPU1_SB_CA<0>
  VSS33  = GND
  CA2_B  = M_E_CPU1_SB_CA<2>
  VSS34  = GND
  CA4_B  = M_E_CPU1_SB_CA<4>
  VSS35  = GND
  CA6_B  = M_E_CPU1_SB_CA<6>
  VSS36  = GND
  CS0_B_N  = M_E_CPU1_SB_CS_N<0>
  VSS37  = GND
  \lbd||rsp_a_n\  = M_E_CPU1_SA_RSP<0>
  \lbs||rsp_b_n\  = M_E_CPU1_SB_RSP<0>
  VSS38  = GND
  CB4_B  = M_E_CPU1_SB_CB<4>
  VSS39  = GND
  CB5_B  = M_E_CPU1_SB_CB<5>
  VSS40  = GND
  \dqs9_b_t||tdqs9_b_t||dbi4_b_n\  = M_E_CPU1_SB_DQS_DP<9>
  \dqs9_b_c||tdqs9_b_c\  = M_E_CPU1_SB_DQS_DN<9>
  VSS41  = GND
  CB0_B  = M_E_CPU1_SB_CB<0>
  VSS42  = GND
  CB1_B  = M_E_CPU1_SB_CB<1>
  VSS43  = GND
  DQ0_B  = M_E_CPU1_SB_DQ<0>
  VSS44  = GND
  DQ1_B  = M_E_CPU1_SB_DQ<1>
  VSS45  = GND
  DQS0_B_T  = M_E_CPU1_SB_DQS_DP<0>
  DQS0_B_C  = M_E_CPU1_SB_DQS_DN<0>
  VSS46  = GND
  DQ4_B  = M_E_CPU1_SB_DQ<4>
  VSS47  = GND
  DQ5_B  = M_E_CPU1_SB_DQ<5>
  VSS48  = GND
  DQ8_B  = M_E_CPU1_SB_DQ<8>
  VSS49  = GND
  DQ9_B  = M_E_CPU1_SB_DQ<9>
  VSS50  = GND
  DQS1_B_T  = M_E_CPU1_SB_DQS_DP<1>
  DQS1_B_C  = M_E_CPU1_SB_DQS_DN<1>
  VSS51  = GND
  DQ12_B  = M_E_CPU1_SB_DQ<12>
  VSS52  = GND
  DQ13_B  = M_E_CPU1_SB_DQ<13>
  VSS53  = GND
  DQ16_B  = M_E_CPU1_SB_DQ<16>
  VSS54  = GND
  DQ17_B  = M_E_CPU1_SB_DQ<17>
  VSS55  = GND
  DQS2_B_T  = M_E_CPU1_SB_DQS_DP<2>
  DQS2_B_C  = M_E_CPU1_SB_DQS_DN<2>
  VSS56  = GND
  DQ20_B  = M_E_CPU1_SB_DQ<20>
  VSS57  = GND
  DQ21_B  = M_E_CPU1_SB_DQ<21>
  VSS58  = GND
  DQ24_B  = M_E_CPU1_SB_DQ<24>
  VSS59  = GND
  DQ25_B  = M_E_CPU1_SB_DQ<25>
  VSS60  = GND
  DQS3_B_T  = M_E_CPU1_SB_DQS_DP<3>
  DQS3_B_C  = M_E_CPU1_SB_DQS_DN<3>
  VSS61  = GND
  DQ28_B  = M_E_CPU1_SB_DQ<28>
  VSS62  = GND
  DQ29_B  = M_E_CPU1_SB_DQ<29>
  VSS63  = GND
  RFU1  = NC
  VIN_BULK1  = P12V_MEM_CPU1
  VIN_BULK2  = P12V_MEM_CPU1
  \pwr_good||fail_n\  = PWRGD_CHE_CPU1_DIMM
  HAS  = PD_CHE_CPU1_DIMM_SAA
  RFU2  = NC
  RFU3  = NC
  VSS64  = GND
  DQ2_A  = M_E_CPU1_SA_DQ<2>
  VSS65  = GND
  DQ3_A  = M_E_CPU1_SA_DQ<3>
  VSS66  = GND
  \dqs5_a_c||tdqs5_a_c||dqs5_a_t||tdqs5_a_t\  = M_E_CPU1_SA_DQS_DN<5>
  \dqs5_a_t||tdqs5_a_t\  = M_E_CPU1_SA_DQS_DP<5>
  VSS67  = GND
  DQ6_A  = M_E_CPU1_SA_DQ<6>
  VSS68  = GND
  DQ7_A  = M_E_CPU1_SA_DQ<7>
  VSS69  = GND
  DQ10_A  = M_E_CPU1_SA_DQ<10>
  VSS70  = GND
  DQ11_A  = M_E_CPU1_SA_DQ<11>
  VSS71  = GND
  \dqs6_a_c||tdqs6_a_c||dqs6_a_t||tdqs6_a_t\  = M_E_CPU1_SA_DQS_DN<6>
  \dqs6_a_t||tdqs6_a_t\  = M_E_CPU1_SA_DQS_DP<6>
  VSS72  = GND
  DQ14_A  = M_E_CPU1_SA_DQ<14>
  VSS73  = GND
  DQ15_A  = M_E_CPU1_SA_DQ<15>
  VSS74  = GND
  DQ18_A  = M_E_CPU1_SA_DQ<18>
  VSS75  = GND
  DQ19_A  = M_E_CPU1_SA_DQ<19>
  VSS76  = GND
  \dqs7_a_c||tdqs7_a_c\  = M_E_CPU1_SA_DQS_DN<7>
  \dqs7_a_t||tdqs7_a_t\  = M_E_CPU1_SA_DQS_DP<7>
  VSS77  = GND
  DQ22_A  = M_E_CPU1_SA_DQ<22>
  VSS78  = GND
  DQ23_A  = M_E_CPU1_SA_DQ<23>
  VSS79  = GND
  DQ26_A  = M_E_CPU1_SA_DQ<26>
  VSS80  = GND
  DQ27_A  = M_E_CPU1_SA_DQ<27>
  VSS81  = GND
  \dqs8_a_c||tdqs8_a_c\  = M_E_CPU1_SA_DQS_DN<8>
  \dqs8_a_t||tdqs8_a_t\  = M_E_CPU1_SA_DQS_DP<8>
  VSS82  = GND
  DQ30_A  = M_E_CPU1_SA_DQ<30>
  VSS83  = GND
  DQ31_A  = M_E_CPU1_SA_DQ<31>
  VSS84  = GND
  CB2_A  = M_E_CPU1_SA_CB<2>
  VSS85  = GND
  CB3_A  = M_E_CPU1_SA_CB<3>
  VSS86  = GND
  \dqs9_a_c||tdqs9_a_c\  = M_E_CPU1_SA_DQS_DN<9>
  \dqs9_a_t||tdqs9_a_t\  = M_E_CPU1_SA_DQS_DP<9>
  VSS87  = GND
  CB6_A  = M_E_CPU1_SA_CB<6>
  VSS88  = GND
  CB7_A  = M_E_CPU1_SA_CB<7>
  VSS89  = GND
  RESET_N  = M_E_CPU1_RESET_N
  VSS90  = GND
  CS1_A_N  = M_E_CPU1_SA_CS_N<1>
  VSS91  = GND
  CA1_A  = M_E_CPU1_SA_CA<1>
  VSS92  = GND
  CA3_A  = M_E_CPU1_SA_CA<3>
  VSS93  = GND
  CA5_A  = M_E_CPU1_SA_CA<5>
  VSS94  = GND
  CK_T  = M_E_CPU1_CLK_DP<0>
  CK_C  = M_E_CPU1_CLK_DN<0>
  VSS95  = GND
  RFU4  = NC
  CA1_B  = M_E_CPU1_SB_CA<1>
  VSS96  = GND
  CA3_B  = M_E_CPU1_SB_CA<3>
  VSS97  = GND
  CA5_B  = M_E_CPU1_SB_CA<5>
  VSS98  = GND
  PAR_B  = M_E_CPU1_SB_PAR
  VSS99  = GND
  CS1_B_N  = M_E_CPU1_SB_CS_N<1>
  VSS100  = GND
  RFU5  = NC
  RFU6  = NC
  VSS101  = GND
  CB6_B  = M_E_CPU1_SB_CB<6>
  VSS102  = GND
  CB7_B  = M_E_CPU1_SB_CB<7>
  VSS103  = GND
  DQS4_B_C  = M_E_CPU1_SB_DQS_DN<4>
  DQS4_B_T  = M_E_CPU1_SB_DQS_DP<4>
  VSS104  = GND
  CB2_B  = M_E_CPU1_SB_CB<2>
  VSS105  = GND
  CB3_B  = M_E_CPU1_SB_CB<3>
  VSS106  = GND
  DQ2_B  = M_E_CPU1_SB_DQ<2>
  VSS107  = GND
  DQ3_B  = M_E_CPU1_SB_DQ<3>
  VSS108  = GND
  \dqs5_b_c||tdqs5_b_c\  = M_E_CPU1_SB_DQS_DN<5>
  \dqs5_b_t||tdqs5_b_t\  = M_E_CPU1_SB_DQS_DP<5>
  VSS109  = GND
  DQ6_B  = M_E_CPU1_SB_DQ<6>
  VSS110  = GND
  DQ7_B  = M_E_CPU1_SB_DQ<7>
  VSS111  = GND
  DQ10_B  = M_E_CPU1_SB_DQ<10>
  VSS112  = GND
  DQ11_B  = M_E_CPU1_SB_DQ<11>
  VSS113  = GND
  \dqs6_b_c||tdqs6_b_c\  = M_E_CPU1_SB_DQS_DN<6>
  \dqs6_b_t||tdqs6_b_t\  = M_E_CPU1_SB_DQS_DP<6>
  VSS114  = GND
  DQ14_B  = M_E_CPU1_SB_DQ<14>
  VSS115  = GND
  DQ15_B  = M_E_CPU1_SB_DQ<15>
  VSS116  = GND
  DQ18_B  = M_E_CPU1_SB_DQ<18>
  VSS117  = GND
  DQ19_B  = M_E_CPU1_SB_DQ<19>
  VSS118  = GND
  \dqs7_b_c||tdqs7_b_c\  = M_E_CPU1_SB_DQS_DN<7>
  \dqs7_b_t||tdqs7_b_t\  = M_E_CPU1_SB_DQS_DP<7>
  VSS119  = GND
  DQ22_B  = M_E_CPU1_SB_DQ<22>
  VSS120  = GND
  DQ23_B  = M_E_CPU1_SB_DQ<23>
  VSS121  = GND
  DQ26_B  = M_E_CPU1_SB_DQ<26>
  VSS122  = GND
  DQ27_B  = M_E_CPU1_SB_DQ<27>
  VSS123  = GND
  \dqs8_b_c||tdqs8_b_c\  = M_E_CPU1_SB_DQS_DN<8>
  \dqs8_b_t||tdqs8_b_t\  = M_E_CPU1_SB_DQS_DP<8>
  VSS124  = GND
  DQ30_B  = M_E_CPU1_SB_DQ<30>
  VSS125  = GND
  DQ31_B  = M_E_CPU1_SB_DQ<31>
  VSS126  = GND
  G1  = GND
  G2  = GND
  G3  = GND

(kicad_pcb
	(version 20260206)
	(generator "pcbnew")
	(generator_version "10.0")
	(general
		(thickness 1.6)
		(legacy_teardrops no)
	)
	(paper "A4")
	(title_block
		(title "04192023_DAF0TMB3IC0_F0TG_MB_C_brd_V02_OCP.brd")
		(comment 1 "Grand Teton / footprint 4612 of 8354 (J32), pads 1-46 of 291")
	)
	(layers
		(0 "F.Cu" signal "TOP")
		(4 "In1.Cu" signal "GND")
		(6 "In2.Cu" signal "IN1")
		(8 "In3.Cu" signal "GND1")
		(10 "In4.Cu" signal "IN2")
		(12 "In5.Cu" signal "GND2")
		(14 "In6.Cu" signal "IN3")
		(16 "In7.Cu" signal "GND3")
		(18 "In8.Cu" signal "VCC")
		(20 "In9.Cu" signal "VCC1")
		(22 "In10.Cu" signal "GND4")
		(24 "In11.Cu" signal "IN4")
		(26 "In12.Cu" signal "GND5")
		(28 "In13.Cu" signal "IN5")
		(30 "In14.Cu" signal "GND6")
		(32 "In15.Cu" signal "IN6")
		(34 "In16.Cu" signal "GND7")
		(2 "B.Cu" signal "BOTTOM")
		(9 "F.Adhes" user "F.Adhesive")
		(11 "B.Adhes" user "B.Adhesive")
		(13 "F.Paste" user "Package Geometry/Pastemask Top")
		(15 "B.Paste" user "Package Geometry/Pastemask Bottom")
		(5 "F.SilkS" user "Ref Des/Silkscreen Top")
		(7 "B.SilkS" user "Ref Des/Silkscreen Bottom")
		(1 "F.Mask" user "Board Geometry/Soldermask Top")
		(3 "B.Mask" user "Board Geometry/Soldermask Bottom")
		(17 "Dwgs.User" user "User.Drawings")
		(19 "Cmts.User" user "User.Comments")
		(21 "Eco1.User" user "User.Eco1")
		(23 "Eco2.User" user "User.Eco2")
		(25 "Edge.Cuts" user "Board Geometry/Outline")
		(27 "Margin" user)
		(31 "F.CrtYd" user "Package Geometry/Place Bound Top")
		(29 "B.CrtYd" user "Package Geometry/Place Bound Bottom")
		(35 "F.Fab" user "Ref Des/Assembly Top")
		(33 "B.Fab" user "Ref Des/Assembly Bottom")
	)
	(footprint ""
		(layer "F.Cu")
		(at 27.20213 -255.560322 180)
		(property "Reference" "J32"
			(at 1.80086 -81.974436 0)
			(unlocked yes)
			(layer "F.SilkS")
			(effects
				(font
					(size 0.7874 0.5842)
					(thickness 0.1524)
				)
			)
		)
		(property "Value" ""
			(at 0 0 180)
			(layer "F.Fab")
			(effects
				(font
					(size 1.27 1.27)
				)
			)
		)
		(duplicate_pad_numbers_are_jumpers no)
		(pad "1" smd rect
			(at -2.050034 -63.324994 90)
			(size 0.519938 1.4986)
			(layers "F.Cu" "F.Mask" "F.Paste")
			(net "P12V_MEM_CPU1")
		)
		(pad "2" smd rect
			(at -2.050034 -62.47511 90)
			(size 0.519938 1.4986)
			(layers "F.Cu" "F.Mask" "F.Paste")
			(net "Net_2312")
		)
		(pad "3" smd rect
			(at -2.050034 -61.624972 90)
			(size 0.519938 1.4986)
			(layers "F.Cu" "F.Mask" "F.Paste")
			(net "P3V3_AUX")
		)
		(pad "4" smd rect
			(at -2.050034 -60.775088 90)
			(size 0.519938 1.4986)
			(layers "F.Cu" "F.Mask" "F.Paste")
			(net "I3C_SPD_DDRE_CPU1_SCL")
		)
		(pad "5" smd rect
			(at -2.050034 -59.92495 90)
			(size 0.519938 1.4986)
			(layers "F.Cu" "F.Mask" "F.Paste")
			(net "I3C_SPD_DDRE_CPU1_SDA")
		)
		(pad "6" smd rect
			(at -2.050034 -59.075066 90)
			(size 0.519938 1.4986)
			(layers "F.Cu" "F.Mask" "F.Paste")
			(net "GND")
		)
		(pad "7" smd rect
			(at -2.050034 -58.224928 90)
			(size 0.519938 1.4986)
			(layers "F.Cu" "F.Mask" "F.Paste")
			(net "M_E_CPU1_SA_DQ<0>")
		)
		(pad "8" smd rect
			(at -2.050034 -57.375044 90)
			(size 0.519938 1.4986)
			(layers "F.Cu" "F.Mask" "F.Paste")
			(net "GND")
		)
		(pad "9" smd rect
			(at -2.050034 -56.524906 90)
			(size 0.519938 1.4986)
			(layers "F.Cu" "F.Mask" "F.Paste")
			(net "M_E_CPU1_SA_DQ<1>")
		)
		(pad "10" smd rect
			(at -2.050034 -55.675022 90)
			(size 0.519938 1.4986)
			(layers "F.Cu" "F.Mask" "F.Paste")
			(net "GND")
		)
		(pad "11" smd rect
			(at -2.050034 -54.824884 90)
			(size 0.519938 1.4986)
			(layers "F.Cu" "F.Mask" "F.Paste")
			(net "M_E_CPU1_SA_DQS_DP<0>")
		)
		(pad "12" smd rect
			(at -2.050034 -53.975 90)
			(size 0.519938 1.4986)
			(layers "F.Cu" "F.Mask" "F.Paste")
			(net "M_E_CPU1_SA_DQS_DN<0>")
		)
		(pad "13" smd rect
			(at -2.050034 -53.125116 90)
			(size 0.519938 1.4986)
			(layers "F.Cu" "F.Mask" "F.Paste")
			(net "GND")
		)
		(pad "14" smd rect
			(at -2.050034 -52.274978 90)
			(size 0.519938 1.4986)
			(layers "F.Cu" "F.Mask" "F.Paste")
			(net "M_E_CPU1_SA_DQ<4>")
		)
		(pad "15" smd rect
			(at -2.050034 -51.425094 90)
			(size 0.519938 1.4986)
			(layers "F.Cu" "F.Mask" "F.Paste")
			(net "GND")
		)
		(pad "16" smd rect
			(at -2.050034 -50.574956 90)
			(size 0.519938 1.4986)
			(layers "F.Cu" "F.Mask" "F.Paste")
			(net "M_E_CPU1_SA_DQ<5>")
		)
		(pad "17" smd rect
			(at -2.050034 -49.725072 90)
			(size 0.519938 1.4986)
			(layers "F.Cu" "F.Mask" "F.Paste")
			(net "GND")
		)
		(pad "18" smd rect
			(at -2.050034 -48.874934 90)
			(size 0.519938 1.4986)
			(layers "F.Cu" "F.Mask" "F.Paste")
			(net "M_E_CPU1_SA_DQ<8>")
		)
		(pad "19" smd rect
			(at -2.050034 -48.02505 90)
			(size 0.519938 1.4986)
			(layers "F.Cu" "F.Mask" "F.Paste")
			(net "GND")
		)
		(pad "20" smd rect
			(at -2.050034 -47.174912 90)
			(size 0.519938 1.4986)
			(layers "F.Cu" "F.Mask" "F.Paste")
			(net "M_E_CPU1_SA_DQ<9>")
		)
		(pad "21" smd rect
			(at -2.050034 -46.325028 90)
			(size 0.519938 1.4986)
			(layers "F.Cu" "F.Mask" "F.Paste")
			(net "GND")
		)
		(pad "22" smd rect
			(at -2.050034 -45.47489 90)
			(size 0.519938 1.4986)
			(layers "F.Cu" "F.Mask" "F.Paste")
			(net "M_E_CPU1_SA_DQS_DP<1>")
		)
		(pad "23" smd rect
			(at -2.050034 -44.625006 90)
			(size 0.519938 1.4986)
			(layers "F.Cu" "F.Mask" "F.Paste")
			(net "M_E_CPU1_SA_DQS_DN<1>")
		)
		(pad "24" smd rect
			(at -2.050034 -43.775122 90)
			(size 0.519938 1.4986)
			(layers "F.Cu" "F.Mask" "F.Paste")
			(net "GND")
		)
		(pad "25" smd rect
			(at -2.050034 -42.924984 90)
			(size 0.519938 1.4986)
			(layers "F.Cu" "F.Mask" "F.Paste")
			(net "M_E_CPU1_SA_DQ<12>")
		)
		(pad "26" smd rect
			(at -2.050034 -42.0751 90)
			(size 0.519938 1.4986)
			(layers "F.Cu" "F.Mask" "F.Paste")
			(net "GND")
		)
		(pad "27" smd rect
			(at -2.050034 -41.224962 90)
			(size 0.519938 1.4986)
			(layers "F.Cu" "F.Mask" "F.Paste")
			(net "M_E_CPU1_SA_DQ<13>")
		)
		(pad "28" smd rect
			(at -2.050034 -40.375078 90)
			(size 0.519938 1.4986)
			(layers "F.Cu" "F.Mask" "F.Paste")
			(net "GND")
		)
		(pad "29" smd rect
			(at -2.050034 -39.52494 90)
			(size 0.519938 1.4986)
			(layers "F.Cu" "F.Mask" "F.Paste")
			(net "M_E_CPU1_SA_DQ<16>")
		)
		(pad "30" smd rect
			(at -2.050034 -38.675056 90)
			(size 0.519938 1.4986)
			(layers "F.Cu" "F.Mask" "F.Paste")
			(net "GND")
		)
		(pad "31" smd rect
			(at -2.050034 -37.824918 90)
			(size 0.519938 1.4986)
			(layers "F.Cu" "F.Mask" "F.Paste")
			(net "M_E_CPU1_SA_DQ<17>")
		)
		(pad "32" smd rect
			(at -2.050034 -36.975034 90)
			(size 0.519938 1.4986)
			(layers "F.Cu" "F.Mask" "F.Paste")
			(net "GND")
		)
		(pad "33" smd rect
			(at -2.050034 -36.124896 90)
			(size 0.519938 1.4986)
			(layers "F.Cu" "F.Mask" "F.Paste")
			(net "M_E_CPU1_SA_DQS_DP<2>")
		)
		(pad "34" smd rect
			(at -2.050034 -35.275012 90)
			(size 0.519938 1.4986)
			(layers "F.Cu" "F.Mask" "F.Paste")
			(net "M_E_CPU1_SA_DQS_DN<2>")
		)
		(pad "35" smd rect
			(at -2.050034 -34.425128 90)
			(size 0.519938 1.4986)
			(layers "F.Cu" "F.Mask" "F.Paste")
			(net "GND")
		)
		(pad "36" smd rect
			(at -2.050034 -33.57499 90)
			(size 0.519938 1.4986)
			(layers "F.Cu" "F.Mask" "F.Paste")
			(net "M_E_CPU1_SA_DQ<20>")
		)
		(pad "37" smd rect
			(at -2.050034 -32.725106 90)
			(size 0.519938 1.4986)
			(layers "F.Cu" "F.Mask" "F.Paste")
			(net "GND")
		)
		(pad "38" smd rect
			(at -2.050034 -31.874968 90)
			(size 0.519938 1.4986)
			(layers "F.Cu" "F.Mask" "F.Paste")
			(net "M_E_CPU1_SA_DQ<21>")
		)
		(pad "39" smd rect
			(at -2.050034 -31.025084 90)
			(size 0.519938 1.4986)
			(layers "F.Cu" "F.Mask" "F.Paste")
			(net "GND")
		)
		(pad "40" smd rect
			(at -2.050034 -30.174946 90)
			(size 0.519938 1.4986)
			(layers "F.Cu" "F.Mask" "F.Paste")
			(net "M_E_CPU1_SA_DQ<24>")
		)
		(pad "41" smd rect
			(at -2.050034 -29.325062 90)
			(size 0.519938 1.4986)
			(layers "F.Cu" "F.Mask" "F.Paste")
			(net "GND")
		)
		(pad "42" smd rect
			(at -2.050034 -28.474924 90)
			(size 0.519938 1.4986)
			(layers "F.Cu" "F.Mask" "F.Paste")
			(net "M_E_CPU1_SA_DQ<25>")
		)
		(pad "43" smd rect
			(at -2.050034 -27.62504 90)
			(size 0.519938 1.4986)
			(layers "F.Cu" "F.Mask" "F.Paste")
			(net "GND")
		)
		(pad "44" smd rect
			(at -2.050034 -26.774902 90)
			(size 0.519938 1.4986)
			(layers "F.Cu" "F.Mask" "F.Paste")
			(net "M_E_CPU1_SA_DQS_DP<3>")
		)
		(pad "45" smd rect
			(at -2.050034 -25.925018 90)
			(size 0.519938 1.4986)
			(layers "F.Cu" "F.Mask" "F.Paste")
			(net "M_E_CPU1_SA_DQS_DN<3>")
		)
		(pad "46" smd rect
			(at -2.050034 -25.07488 90)
			(size 0.519938 1.4986)
			(layers "F.Cu" "F.Mask" "F.Paste")
			(net "GND")
		)
	)
)
